# T6G (Grand Teton) — schematic netlist excerpt (pin names and nets, part order shuffled) for the footprints in the layout excerpt that follows; sources: Cadence DE-HDL packaged netlist, KiCad conversion of 04192023_DAF0TMB3IC0_F0TG_MB_C_brd_V02_OCP.brd

J69  SCONN288_DDR506112002KQ  IO  pkg DDR288S_1-1VXC  page 93
  VIN_BULK0  = P12V_MEM_CPU0
  RFU0  = NC
  VIN_MGMT  = P3V3_AUX
  HSCL  = I3C_SPD_DDRH_CPU0_SCL
  HSDA  = I3C_SPD_DDRH_CPU0_SDA
  VSS0  = GND
  DQ0_A  = M_H_CPU0_SA_DQ<0>
  VSS1  = GND
  DQ1_A  = M_H_CPU0_SA_DQ<1>
  VSS2  = GND
  DQS0_A_T  = M_H_CPU0_SA_DQS_DP<0>
  DQS0_A_C  = M_H_CPU0_SA_DQS_DN<0>
  VSS3  = GND
  DQ4_A  = M_H_CPU0_SA_DQ<4>
  VSS4  = GND
  DQ5_A  = M_H_CPU0_SA_DQ<5>
  VSS5  = GND
  DQ8_A  = M_H_CPU0_SA_DQ<8>
  VSS6  = GND
  DQ9_A  = M_H_CPU0_SA_DQ<9>
  VSS7  = GND
  DQS1_A_T  = M_H_CPU0_SA_DQS_DP<1>
  DQS1_A_C  = M_H_CPU0_SA_DQS_DN<1>
  VSS8  = GND
  DQ12_A  = M_H_CPU0_SA_DQ<12>
  VSS9  = GND
  DQ13_A  = M_H_CPU0_SA_DQ<13>
  VSS10  = GND
  DQ16_A  = M_H_CPU0_SA_DQ<16>
  VSS11  = GND
  DQ17_A  = M_H_CPU0_SA_DQ<17>
  VSS12  = GND
  DQS2_A_T  = M_H_CPU0_SA_DQS_DP<2>
  DQS2_A_C  = M_H_CPU0_SA_DQS_DN<2>
  VSS13  = GND
  DQ20_A  = M_H_CPU0_SA_DQ<20>
  VSS14  = GND
  DQ21_A  = M_H_CPU0_SA_DQ<21>
  VSS15  = GND
  DQ24_A  = M_H_CPU0_SA_DQ<24>
  VSS16  = GND
  DQ25_A  = M_H_CPU0_SA_DQ<25>
  VSS17  = GND
  DQS3_A_T  = M_H_CPU0_SA_DQS_DP<3>
  DQS3_A_C  = M_H_CPU0_SA_DQS_DN<3>
  VSS18  = GND
  DQ28_A  = M_H_CPU0_SA_DQ<28>
  VSS19  = GND
  DQ29_A  = M_H_CPU0_SA_DQ<29>
  VSS20  = GND
  CB0_A  = M_H_CPU0_SA_CB<0>
  VSS21  = GND
  CB1_A  = M_H_CPU0_SA_CB<1>
  VSS22  = GND
  DQS4_A_T  = M_H_CPU0_SA_DQS_DP<4>
  DQS4_A_C  = M_H_CPU0_SA_DQS_DN<4>
  VSS23  = GND
  CB4_A  = M_H_CPU0_SA_CB<4>
  VSS24  = GND
  CB5_A  = M_H_CPU0_SA_CB<5>
  VSS25  = GND
  ALERT_N  = M_H_CPU0_ALERT_N
  VSS26  = GND
  CS0_A_N  = M_H_CPU0_SA_CS_N<0>
  VSS27  = GND
  CA0_A  = M_H_CPU0_SA_CA<0>
  VSS28  = GND
  CA2_A  = M_H_CPU0_SA_CA<2>
  VSS29  = GND
  CA4_A  = M_H_CPU0_SA_CA<4>
  VSS30  = GND
  CA6_A  = M_H_CPU0_SA_CA<6>
  VSS31  = GND
  PAR_A  = M_H_CPU0_SA_PAR
  VSS32  = GND
  CA0_B  = M_H_CPU0_SB_CA<0>
  VSS33  = GND
  CA2_B  = M_H_CPU0_SB_CA<2>
  VSS34  = GND
  CA4_B  = M_H_CPU0_SB_CA<4>
  VSS35  = GND
  CA6_B  = M_H_CPU0_SB_CA<6>
  VSS36  = GND
  CS0_B_N  = M_H_CPU0_SB_CS_N<0>
  VSS37  = GND
  \lbd||rsp_a_n\  = M_H_CPU0_SA_RSP<0>
  \lbs||rsp_b_n\  = M_H_CPU0_SB_RSP<0>
  VSS38  = GND
  CB4_B  = M_H_CPU0_SB_CB<4>
  VSS39  = GND
  CB5_B  = M_H_CPU0_SB_CB<5>
  VSS40  = GND
  \dqs9_b_t||tdqs9_b_t||dbi4_b_n\  = M_H_CPU0_SB_DQS_DP<9>
  \dqs9_b_c||tdqs9_b_c\  = M_H_CPU0_SB_DQS_DN<9>
  VSS41  = GND
  CB0_B  = M_H_CPU0_SB_CB<0>
  VSS42  = GND
  CB1_B  = M_H_CPU0_SB_CB<1>
  VSS43  = GND
  DQ0_B  = M_H_CPU0_SB_DQ<0>
  VSS44  = GND
  DQ1_B  = M_H_CPU0_SB_DQ<1>
  VSS45  = GND
  DQS0_B_T  = M_H_CPU0_SB_DQS_DP<0>
  DQS0_B_C  = M_H_CPU0_SB_DQS_DN<0>
  VSS46  = GND
  DQ4_B  = M_H_CPU0_SB_DQ<4>
  VSS47  = GND
  DQ5_B  = M_H_CPU0_SB_DQ<5>
  VSS48  = GND
  DQ8_B  = M_H_CPU0_SB_DQ<8>
  VSS49  = GND
  DQ9_B  = M_H_CPU0_SB_DQ<9>
  VSS50  = GND
  DQS1_B_T  = M_H_CPU0_SB_DQS_DP<1>
  DQS1_B_C  = M_H_CPU0_SB_DQS_DN<1>
  VSS51  = GND
  DQ12_B  = M_H_CPU0_SB_DQ<12>
  VSS52  = GND
  DQ13_B  = M_H_CPU0_SB_DQ<13>
  VSS53  = GND
  DQ16_B  = M_H_CPU0_SB_DQ<16>
  VSS54  = GND
  DQ17_B  = M_H_CPU0_SB_DQ<17>
  VSS55  = GND
  DQS2_B_T  = M_H_CPU0_SB_DQS_DP<2>
  DQS2_B_C  = M_H_CPU0_SB_DQS_DN<2>
  VSS56  = GND
  DQ20_B  = M_H_CPU0_SB_DQ<20>
  VSS57  = GND
  DQ21_B  = M_H_CPU0_SB_DQ<21>
  VSS58  = GND
  DQ24_B  = M_H_CPU0_SB_DQ<24>
  VSS59  = GND
  DQ25_B  = M_H_CPU0_SB_DQ<25>
  VSS60  = GND
  DQS3_B_T  = M_H_CPU0_SB_DQS_DP<3>
  DQS3_B_C  = M_H_CPU0_SB_DQS_DN<3>
  VSS61  = GND
  DQ28_B  = M_H_CPU0_SB_DQ<28>
  VSS62  = GND
  DQ29_B  = M_H_CPU0_SB_DQ<29>
  VSS63  = GND
  RFU1  = NC
  VIN_BULK1  = P12V_MEM_CPU0
  VIN_BULK2  = P12V_MEM_CPU0
  \pwr_good||fail_n\  = PWRGD_CHH_CPU0_DIMM
  HAS  = PD_CHH_CPU0_DIMM_SAA
  RFU2  = NC
  RFU3  = NC
  VSS64  = GND
  DQ2_A  = M_H_CPU0_SA_DQ<2>
  VSS65  = GND
  DQ3_A  = M_H_CPU0_SA_DQ<3>
  VSS66  = GND
  \dqs5_a_c||tdqs5_a_c||dqs5_a_t||tdqs5_a_t\  = M_H_CPU0_SA_DQS_DN<5>
  \dqs5_a_t||tdqs5_a_t\  = M_H_CPU0_SA_DQS_DP<5>
  VSS67  = GND
  DQ6_A  = M_H_CPU0_SA_DQ<6>
  VSS68  = GND
  DQ7_A  = M_H_CPU0_SA_DQ<7>
  VSS69  = GND
  DQ10_A  = M_H_CPU0_SA_DQ<10>
  VSS70  = GND
  DQ11_A  = M_H_CPU0_SA_DQ<11>
  VSS71  = GND
  \dqs6_a_c||tdqs6_a_c||dqs6_a_t||tdqs6_a_t\  = M_H_CPU0_SA_DQS_DN<6>
  \dqs6_a_t||tdqs6_a_t\  = M_H_CPU0_SA_DQS_DP<6>
  VSS72  = GND
  DQ14_A  = M_H_CPU0_SA_DQ<14>
  VSS73  = GND
  DQ15_A  = M_H_CPU0_SA_DQ<15>
  VSS74  = GND
  DQ18_A  = M_H_CPU0_SA_DQ<18>
  VSS75  = GND
  DQ19_A  = M_H_CPU0_SA_DQ<19>
  VSS76  = GND
  \dqs7_a_c||tdqs7_a_c\  = M_H_CPU0_SA_DQS_DN<7>
  \dqs7_a_t||tdqs7_a_t\  = M_H_CPU0_SA_DQS_DP<7>
  VSS77  = GND
  DQ22_A  = M_H_CPU0_SA_DQ<22>
  VSS78  = GND
  DQ23_A  = M_H_CPU0_SA_DQ<23>
  VSS79  = GND
  DQ26_A  = M_H_CPU0_SA_DQ<26>
  VSS80  = GND
  DQ27_A  = M_H_CPU0_SA_DQ<27>
  VSS81  = GND
  \dqs8_a_c||tdqs8_a_c\  = M_H_CPU0_SA_DQS_DN<8>
  \dqs8_a_t||tdqs8_a_t\  = M_H_CPU0_SA_DQS_DP<8>
  VSS82  = GND
  DQ30_A  = M_H_CPU0_SA_DQ<30>
  VSS83  = GND
  DQ31_A  = M_H_CPU0_SA_DQ<31>
  VSS84  = GND
  CB2_A  = M_H_CPU0_SA_CB<2>
  VSS85  = GND
  CB3_A  = M_H_CPU0_SA_CB<3>
  VSS86  = GND
  \dqs9_a_c||tdqs9_a_c\  = M_H_CPU0_SA_DQS_DN<9>
  \dqs9_a_t||tdqs9_a_t\  = M_H_CPU0_SA_DQS_DP<9>
  VSS87  = GND
  CB6_A  = M_H_CPU0_SA_CB<6>
  VSS88  = GND
  CB7_A  = M_H_CPU0_SA_CB<7>
  VSS89  = GND
  RESET_N  = M_H_CPU0_RESET_N
  VSS90  = GND
  CS1_A_N  = M_H_CPU0_SA_CS_N<1>
  VSS91  = GND
  CA1_A  = M_H_CPU0_SA_CA<1>
  VSS92  = GND
  CA3_A  = M_H_CPU0_SA_CA<3>
  VSS93  = GND
  CA5_A  = M_H_CPU0_SA_CA<5>
  VSS94  = GND
  CK_T  = M_H_CPU0_CLK_DP<0>
  CK_C  = M_H_CPU0_CLK_DN<0>
  VSS95  = GND
  RFU4  = NC
  CA1_B  = M_H_CPU0_SB_CA<1>
  VSS96  = GND
  CA3_B  = M_H_CPU0_SB_CA<3>
  VSS97  = GND
  CA5_B  = M_H_CPU0_SB_CA<5>
  VSS98  = GND
  PAR_B  = M_H_CPU0_SB_PAR
  VSS99  = GND
  CS1_B_N  = M_H_CPU0_SB_CS_N<1>
  VSS100  = GND
  RFU5  = NC
  RFU6  = NC
  VSS101  = GND
  CB6_B  = M_H_CPU0_SB_CB<6>
  VSS102  = GND
  CB7_B  = M_H_CPU0_SB_CB<7>
  VSS103  = GND
  DQS4_B_C  = M_H_CPU0_SB_DQS_DN<4>
  DQS4_B_T  = M_H_CPU0_SB_DQS_DP<4>
  VSS104  = GND
  CB2_B  = M_H_CPU0_SB_CB<2>
  VSS105  = GND
  CB3_B  = M_H_CPU0_SB_CB<3>
  VSS106  = GND
  DQ2_B  = M_H_CPU0_SB_DQ<2>
  VSS107  = GND
  DQ3_B  = M_H_CPU0_SB_DQ<3>
  VSS108  = GND
  \dqs5_b_c||tdqs5_b_c\  = M_H_CPU0_SB_DQS_DN<5>
  \dqs5_b_t||tdqs5_b_t\  = M_H_CPU0_SB_DQS_DP<5>
  VSS109  = GND
  DQ6_B  = M_H_CPU0_SB_DQ<6>
  VSS110  = GND
  DQ7_B  = M_H_CPU0_SB_DQ<7>
  VSS111  = GND
  DQ10_B  = M_H_CPU0_SB_DQ<10>
  VSS112  = GND
  DQ11_B  = M_H_CPU0_SB_DQ<11>
  VSS113  = GND
  \dqs6_b_c||tdqs6_b_c\  = M_H_CPU0_SB_DQS_DN<6>
  \dqs6_b_t||tdqs6_b_t\  = M_H_CPU0_SB_DQS_DP<6>
  VSS114  = GND
  DQ14_B  = M_H_CPU0_SB_DQ<14>
  VSS115  = GND
  DQ15_B  = M_H_CPU0_SB_DQ<15>
  VSS116  = GND
  DQ18_B  = M_H_CPU0_SB_DQ<18>
  VSS117  = GND
  DQ19_B  = M_H_CPU0_SB_DQ<19>
  VSS118  = GND
  \dqs7_b_c||tdqs7_b_c\  = M_H_CPU0_SB_DQS_DN<7>
  \dqs7_b_t||tdqs7_b_t\  = M_H_CPU0_SB_DQS_DP<7>
  VSS119  = GND
  DQ22_B  = M_H_CPU0_SB_DQ<22>
  VSS120  = GND
  DQ23_B  = M_H_CPU0_SB_DQ<23>
  VSS121  = GND
  DQ26_B  = M_H_CPU0_SB_DQ<26>
  VSS122  = GND
  DQ27_B  = M_H_CPU0_SB_DQ<27>
  VSS123  = GND
  \dqs8_b_c||tdqs8_b_c\  = M_H_CPU0_SB_DQS_DN<8>
  \dqs8_b_t||tdqs8_b_t\  = M_H_CPU0_SB_DQS_DP<8>
  VSS124  = GND
  DQ30_B  = M_H_CPU0_SB_DQ<30>
  VSS125  = GND
  DQ31_B  = M_H_CPU0_SB_DQ<31>
  VSS126  = GND
  G1  = GND
  G2  = GND
  G3  = GND

(kicad_pcb
	(version 20260206)
	(generator "pcbnew")
	(generator_version "10.0")
	(general
		(thickness 1.6)
		(legacy_teardrops no)
	)
	(paper "A4")
	(title_block
		(title "04192023_DAF0TMB3IC0_F0TG_MB_C_brd_V02_OCP.brd")
		(comment 1 "Grand Teton / footprint 2335 of 8354 (J69), pads 93-138 of 291")
	)
	(layers
		(0 "F.Cu" signal "TOP")
		(4 "In1.Cu" signal "GND")
		(6 "In2.Cu" signal "IN1")
		(8 "In3.Cu" signal "GND1")
		(10 "In4.Cu" signal "IN2")
		(12 "In5.Cu" signal "GND2")
		(14 "In6.Cu" signal "IN3")
		(16 "In7.Cu" signal "GND3")
		(18 "In8.Cu" signal "VCC")
		(20 "In9.Cu" signal "VCC1")
		(22 "In10.Cu" signal "GND4")
		(24 "In11.Cu" signal "IN4")
		(26 "In12.Cu" signal "GND5")
		(28 "In13.Cu" signal "IN5")
		(30 "In14.Cu" signal "GND6")
		(32 "In15.Cu" signal "IN6")
		(34 "In16.Cu" signal "GND7")
		(2 "B.Cu" signal "BOTTOM")
		(9 "F.Adhes" user "F.Adhesive")
		(11 "B.Adhes" user "B.Adhesive")
		(13 "F.Paste" user "Package Geometry/Pastemask Top")
		(15 "B.Paste" user "Package Geometry/Pastemask Bottom")
		(5 "F.SilkS" user "Ref Des/Silkscreen Top")
		(7 "B.SilkS" user "Ref Des/Silkscreen Bottom")
		(1 "F.Mask" user "Board Geometry/Soldermask Top")
		(3 "B.Mask" user "Board Geometry/Soldermask Bottom")
		(17 "Dwgs.User" user "User.Drawings")
		(19 "Cmts.User" user "User.Comments")
		(21 "Eco1.User" user "User.Eco1")
		(23 "Eco2.User" user "User.Eco2")
		(25 "Edge.Cuts" user "Board Geometry/Outline")
		(27 "Margin" user)
		(31 "F.CrtYd" user "Package Geometry/Place Bound Top")
		(29 "B.CrtYd" user "Package Geometry/Place Bound Bottom")
		(35 "F.Fab" user "Ref Des/Assembly Top")
		(33 "B.Fab" user "Ref Des/Assembly Bottom")
	)
	(footprint ""
		(layer "F.Cu")
		(at 421.962072 -255.560068 180)
		(property "Reference" "J69"
			(at 3.448304 81.947512 0)
			(unlocked yes)
			(layer "F.SilkS")
			(effects
				(font
					(size 0.7874 0.5842)
					(thickness 0.1524)
				)
			)
		)
		(property "Value" ""
			(at 0 0 180)
			(layer "F.Fab")
			(effects
				(font
					(size 1.27 1.27)
				)
			)
		)
		(duplicate_pad_numbers_are_jumpers no)
		(pad "93" smd rect
			(at -2.050034 19.975068 90)
			(size 0.519938 1.4986)
			(layers "F.Cu" "F.Mask" "F.Paste")
			(net "M_H_CPU0_SB_DQS_DP<9>")
		)
		(pad "94" smd rect
			(at -2.050034 20.824952 90)
			(size 0.519938 1.4986)
			(layers "F.Cu" "F.Mask" "F.Paste")
			(net "M_H_CPU0_SB_DQS_DN<9>")
		)
		(pad "95" smd rect
			(at -2.050034 21.67509 90)
			(size 0.519938 1.4986)
			(layers "F.Cu" "F.Mask" "F.Paste")
			(net "GND")
		)
		(pad "96" smd rect
			(at -2.050034 22.524974 90)
			(size 0.519938 1.4986)
			(layers "F.Cu" "F.Mask" "F.Paste")
			(net "M_H_CPU0_SB_CB<0>")
		)
		(pad "97" smd rect
			(at -2.050034 23.375112 90)
			(size 0.519938 1.4986)
			(layers "F.Cu" "F.Mask" "F.Paste")
			(net "GND")
		)
		(pad "98" smd rect
			(at -2.050034 24.224996 90)
			(size 0.519938 1.4986)
			(layers "F.Cu" "F.Mask" "F.Paste")
			(net "M_H_CPU0_SB_CB<1>")
		)
		(pad "99" smd rect
			(at -2.050034 25.07488 90)
			(size 0.519938 1.4986)
			(layers "F.Cu" "F.Mask" "F.Paste")
			(net "GND")
		)
		(pad "100" smd rect
			(at -2.050034 25.925018 90)
			(size 0.519938 1.4986)
			(layers "F.Cu" "F.Mask" "F.Paste")
			(net "M_H_CPU0_SB_DQ<0>")
		)
		(pad "101" smd rect
			(at -2.050034 26.774902 90)
			(size 0.519938 1.4986)
			(layers "F.Cu" "F.Mask" "F.Paste")
			(net "GND")
		)
		(pad "102" smd rect
			(at -2.050034 27.62504 90)
			(size 0.519938 1.4986)
			(layers "F.Cu" "F.Mask" "F.Paste")
			(net "M_H_CPU0_SB_DQ<1>")
		)
		(pad "103" smd rect
			(at -2.050034 28.474924 90)
			(size 0.519938 1.4986)
			(layers "F.Cu" "F.Mask" "F.Paste")
			(net "GND")
		)
		(pad "104" smd rect
			(at -2.050034 29.325062 90)
			(size 0.519938 1.4986)
			(layers "F.Cu" "F.Mask" "F.Paste")
			(net "M_H_CPU0_SB_DQS_DP<0>")
		)
		(pad "105" smd rect
			(at -2.050034 30.174946 90)
			(size 0.519938 1.4986)
			(layers "F.Cu" "F.Mask" "F.Paste")
			(net "M_H_CPU0_SB_DQS_DN<0>")
		)
		(pad "106" smd rect
			(at -2.050034 31.025084 90)
			(size 0.519938 1.4986)
			(layers "F.Cu" "F.Mask" "F.Paste")
			(net "GND")
		)
		(pad "107" smd rect
			(at -2.050034 31.874968 90)
			(size 0.519938 1.4986)
			(layers "F.Cu" "F.Mask" "F.Paste")
			(net "M_H_CPU0_SB_DQ<4>")
		)
		(pad "108" smd rect
			(at -2.050034 32.725106 90)
			(size 0.519938 1.4986)
			(layers "F.Cu" "F.Mask" "F.Paste")
			(net "GND")
		)
		(pad "109" smd rect
			(at -2.050034 33.57499 90)
			(size 0.519938 1.4986)
			(layers "F.Cu" "F.Mask" "F.Paste")
			(net "M_H_CPU0_SB_DQ<5>")
		)
		(pad "110" smd rect
			(at -2.050034 34.425128 90)
			(size 0.519938 1.4986)
			(layers "F.Cu" "F.Mask" "F.Paste")
			(net "GND")
		)
		(pad "111" smd rect
			(at -2.050034 35.275012 90)
			(size 0.519938 1.4986)
			(layers "F.Cu" "F.Mask" "F.Paste")
			(net "M_H_CPU0_SB_DQ<8>")
		)
		(pad "112" smd rect
			(at -2.050034 36.124896 90)
			(size 0.519938 1.4986)
			(layers "F.Cu" "F.Mask" "F.Paste")
			(net "GND")
		)
		(pad "113" smd rect
			(at -2.050034 36.975034 90)
			(size 0.519938 1.4986)
			(layers "F.Cu" "F.Mask" "F.Paste")
			(net "M_H_CPU0_SB_DQ<9>")
		)
		(pad "114" smd rect
			(at -2.050034 37.824918 90)
			(size 0.519938 1.4986)
			(layers "F.Cu" "F.Mask" "F.Paste")
			(net "GND")
		)
		(pad "115" smd rect
			(at -2.050034 38.675056 90)
			(size 0.519938 1.4986)
			(layers "F.Cu" "F.Mask" "F.Paste")
			(net "M_H_CPU0_SB_DQS_DP<1>")
		)
		(pad "116" smd rect
			(at -2.050034 39.52494 90)
			(size 0.519938 1.4986)
			(layers "F.Cu" "F.Mask" "F.Paste")
			(net "M_H_CPU0_SB_DQS_DN<1>")
		)
		(pad "117" smd rect
			(at -2.050034 40.375078 90)
			(size 0.519938 1.4986)
			(layers "F.Cu" "F.Mask" "F.Paste")
			(net "GND")
		)
		(pad "118" smd rect
			(at -2.050034 41.224962 90)
			(size 0.519938 1.4986)
			(layers "F.Cu" "F.Mask" "F.Paste")
			(net "M_H_CPU0_SB_DQ<12>")
		)
		(pad "119" smd rect
			(at -2.050034 42.0751 90)
			(size 0.519938 1.4986)
			(layers "F.Cu" "F.Mask" "F.Paste")
			(net "GND")
		)
		(pad "120" smd rect
			(at -2.050034 42.924984 90)
			(size 0.519938 1.4986)
			(layers "F.Cu" "F.Mask" "F.Paste")
			(net "M_H_CPU0_SB_DQ<13>")
		)
		(pad "121" smd rect
			(at -2.050034 43.775122 90)
			(size 0.519938 1.4986)
			(layers "F.Cu" "F.Mask" "F.Paste")
			(net "GND")
		)
		(pad "122" smd rect
			(at -2.050034 44.625006 90)
			(size 0.519938 1.4986)
			(layers "F.Cu" "F.Mask" "F.Paste")
			(net "M_H_CPU0_SB_DQ<16>")
		)
		(pad "123" smd rect
			(at -2.050034 45.47489 90)
			(size 0.519938 1.4986)
			(layers "F.Cu" "F.Mask" "F.Paste")
			(net "GND")
		)
		(pad "124" smd rect
			(at -2.050034 46.325028 90)
			(size 0.519938 1.4986)
			(layers "F.Cu" "F.Mask" "F.Paste")
			(net "M_H_CPU0_SB_DQ<17>")
		)
		(pad "125" smd rect
			(at -2.050034 47.174912 90)
			(size 0.519938 1.4986)
			(layers "F.Cu" "F.Mask" "F.Paste")
			(net "GND")
		)
		(pad "126" smd rect
			(at -2.050034 48.02505 90)
			(size 0.519938 1.4986)
			(layers "F.Cu" "F.Mask" "F.Paste")
			(net "M_H_CPU0_SB_DQS_DP<2>")
		)
		(pad "127" smd rect
			(at -2.050034 48.874934 90)
			(size 0.519938 1.4986)
			(layers "F.Cu" "F.Mask" "F.Paste")
			(net "M_H_CPU0_SB_DQS_DN<2>")
		)
		(pad "128" smd rect
			(at -2.050034 49.725072 90)
			(size 0.519938 1.4986)
			(layers "F.Cu" "F.Mask" "F.Paste")
			(net "GND")
		)
		(pad "129" smd rect
			(at -2.050034 50.574956 90)
			(size 0.519938 1.4986)
			(layers "F.Cu" "F.Mask" "F.Paste")
			(net "M_H_CPU0_SB_DQ<20>")
		)
		(pad "130" smd rect
			(at -2.050034 51.425094 90)
			(size 0.519938 1.4986)
			(layers "F.Cu" "F.Mask" "F.Paste")
			(net "GND")
		)
		(pad "131" smd rect
			(at -2.050034 52.274978 90)
			(size 0.519938 1.4986)
			(layers "F.Cu" "F.Mask" "F.Paste")
			(net "M_H_CPU0_SB_DQ<21>")
		)
		(pad "132" smd rect
			(at -2.050034 53.125116 90)
			(size 0.519938 1.4986)
			(layers "F.Cu" "F.Mask" "F.Paste")
			(net "GND")
		)
		(pad "133" smd rect
			(at -2.050034 53.975 90)
			(size 0.519938 1.4986)
			(layers "F.Cu" "F.Mask" "F.Paste")
			(net "M_H_CPU0_SB_DQ<24>")
		)
		(pad "134" smd rect
			(at -2.050034 54.824884 90)
			(size 0.519938 1.4986)
			(layers "F.Cu" "F.Mask" "F.Paste")
			(net "GND")
		)
		(pad "135" smd rect
			(at -2.050034 55.675022 90)
			(size 0.519938 1.4986)
			(layers "F.Cu" "F.Mask" "F.Paste")
			(net "M_H_CPU0_SB_DQ<25>")
		)
		(pad "136" smd rect
			(at -2.050034 56.524906 90)
			(size 0.519938 1.4986)
			(layers "F.Cu" "F.Mask" "F.Paste")
			(net "GND")
		)
		(pad "137" smd rect
			(at -2.050034 57.375044 90)
			(size 0.519938 1.4986)
			(layers "F.Cu" "F.Mask" "F.Paste")
			(net "M_H_CPU0_SB_DQS_DP<3>")
		)
		(pad "138" smd rect
			(at -2.050034 58.224928 90)
			(size 0.519938 1.4986)
			(layers "F.Cu" "F.Mask" "F.Paste")
			(net "M_H_CPU0_SB_DQS_DN<3>")
		)
	)
)
